# T6G (Grand Teton) — schematic netlist excerpt (pin names and nets, part order shuffled) for the footprints in the layout excerpt that follows; sources: Cadence DE-HDL packaged netlist, KiCad conversion of 04192023_DAF0TMB3IC0_F0TG_MB_C_brd_V02_OCP.brd

R80  Q_RES  100K 1% CHIP  pkg 0402LF  page 132 : A = RMII_OCP_BMC_RXD_1 ; B = GND
R8056  Q_RES  1K 1% CHIP  pkg 0402LF  page 200 : A = P3V3_AUX ; B = PWRGD_PVDDCR_CPU1_P0_R

(kicad_pcb
	(version 20260206)
	(generator "pcbnew")
	(generator_version "10.0")
	(general
		(thickness 1.6)
		(legacy_teardrops no)
	)
	(paper "A4")
	(title_block
		(title "04192023_DAF0TMB3IC0_F0TG_MB_C_brd_V02_OCP.brd")
		(comment 1 "Grand Teton / footprints 837-838 of 8354")
	)
	(layers
		(0 "F.Cu" signal "TOP")
		(4 "In1.Cu" signal "GND")
		(6 "In2.Cu" signal "IN1")
		(8 "In3.Cu" signal "GND1")
		(10 "In4.Cu" signal "IN2")
		(12 "In5.Cu" signal "GND2")
		(14 "In6.Cu" signal "IN3")
		(16 "In7.Cu" signal "GND3")
		(18 "In8.Cu" signal "VCC")
		(20 "In9.Cu" signal "VCC1")
		(22 "In10.Cu" signal "GND4")
		(24 "In11.Cu" signal "IN4")
		(26 "In12.Cu" signal "GND5")
		(28 "In13.Cu" signal "IN5")
		(30 "In14.Cu" signal "GND6")
		(32 "In15.Cu" signal "IN6")
		(34 "In16.Cu" signal "GND7")
		(2 "B.Cu" signal "BOTTOM")
		(9 "F.Adhes" user "F.Adhesive")
		(11 "B.Adhes" user "B.Adhesive")
		(13 "F.Paste" user "Package Geometry/Pastemask Top")
		(15 "B.Paste" user "Package Geometry/Pastemask Bottom")
		(5 "F.SilkS" user "Ref Des/Silkscreen Top")
		(7 "B.SilkS" user "Ref Des/Silkscreen Bottom")
		(1 "F.Mask" user "Board Geometry/Soldermask Top")
		(3 "B.Mask" user "Board Geometry/Soldermask Bottom")
		(17 "Dwgs.User" user "User.Drawings")
		(19 "Cmts.User" user "User.Comments")
		(21 "Eco1.User" user "User.Eco1")
		(23 "Eco2.User" user "User.Eco2")
		(25 "Edge.Cuts" user "Board Geometry/Outline")
		(27 "Margin" user)
		(31 "F.CrtYd" user "Package Geometry/Place Bound Top")
		(29 "B.CrtYd" user "Package Geometry/Place Bound Bottom")
		(35 "F.Fab" user "Ref Des/Assembly Top")
		(33 "B.Fab" user "Ref Des/Assembly Bottom")
	)
	(footprint ""
		(layer "F.Cu")
		(at 196.708268 -78.42377 180)
		(property "Reference" "R80"
			(at 0 0 180)
			(layer "F.SilkS")
			(hide yes)
			(effects
				(font
					(size 1.27 1.27)
				)
			)
		)
		(property "Value" ""
			(at 0 0 180)
			(layer "F.Fab")
			(effects
				(font
					(size 1.27 1.27)
				)
			)
		)
		(duplicate_pad_numbers_are_jumpers no)
		(fp_line
			(start 0.7874 0.4064)
			(end -0.7874 0.4064)
			(stroke
				(width 0.1524)
				(type default)
			)
			(layer "F.SilkS")
		)
		(fp_line
			(start 0.7874 -0.4064)
			(end 0.7874 0.4064)
			(stroke
				(width 0.1524)
				(type default)
			)
			(layer "F.SilkS")
		)
		(fp_line
			(start -0.7874 0.4064)
			(end -0.7874 -0.4064)
			(stroke
				(width 0.1524)
				(type default)
			)
			(layer "F.SilkS")
		)
		(fp_line
			(start -0.7874 -0.4064)
			(end 0.7874 -0.4064)
			(stroke
				(width 0.1524)
				(type default)
			)
			(layer "F.SilkS")
		)
		(fp_line
			(start 0.67945 0.3048)
			(end 0.120396 0.3048)
			(stroke
				(width 0.1)
				(type default)
			)
			(layer "F.Fab")
		)
		(fp_line
			(start 0.67945 -0.3048)
			(end 0.67945 0.3048)
			(stroke
				(width 0.1)
				(type default)
			)
			(layer "F.Fab")
		)
		(fp_line
			(start 0.12065 -0.2794)
			(end 0.12065 -0.3048)
			(stroke
				(width 0.1)
				(type default)
			)
			(layer "F.Fab")
		)
		(fp_line
			(start 0.12065 -0.3048)
			(end 0.67945 -0.3048)
			(stroke
				(width 0.1)
				(type default)
			)
			(layer "F.Fab")
		)
		(fp_line
			(start 0.120396 0.3048)
			(end 0.120396 0.2794)
			(stroke
				(width 0.1)
				(type default)
			)
			(layer "F.Fab")
		)
		(fp_line
			(start 0.120396 0.2794)
			(end -0.12065 0.2794)
			(stroke
				(width 0.1)
				(type default)
			)
			(layer "F.Fab")
		)
		(fp_line
			(start -0.12065 0.3048)
			(end -0.67945 0.3048)
			(stroke
				(width 0.1)
				(type default)
			)
			(layer "F.Fab")
		)
		(fp_line
			(start -0.12065 0.2794)
			(end -0.12065 0.3048)
			(stroke
				(width 0.1)
				(type default)
			)
			(layer "F.Fab")
		)
		(fp_line
			(start -0.12065 -0.2794)
			(end 0.12065 -0.2794)
			(stroke
				(width 0.1)
				(type default)
			)
			(layer "F.Fab")
		)
		(fp_line
			(start -0.12065 -0.305054)
			(end -0.12065 -0.2794)
			(stroke
				(width 0.1)
				(type default)
			)
			(layer "F.Fab")
		)
		(fp_line
			(start -0.67945 0.3048)
			(end -0.67945 -0.305054)
			(stroke
				(width 0.1)
				(type default)
			)
			(layer "F.Fab")
		)
		(fp_line
			(start -0.67945 -0.305054)
			(end -0.12065 -0.305054)
			(stroke
				(width 0.1)
				(type default)
			)
			(layer "F.Fab")
		)
		(pad "1" smd circle
			(at -0.40005 0 180)
			(size 0 0)
			(layers "F.Cu" "F.Mask" "F.Paste")
			(net "RMII_OCP_BMC_RXD_1")
		)
		(pad "2" smd circle
			(at 0.40005 0 180)
			(size 0 0)
			(layers "F.Cu" "F.Mask" "F.Paste")
			(net "GND")
		)
	)
	(footprint ""
		(layer "F.Cu")
		(at 302.1584 -362.839)
		(property "Reference" "R8056"
			(at 0 0 0)
			(layer "F.SilkS")
			(hide yes)
			(effects
				(font
					(size 1.27 1.27)
				)
			)
		)
		(property "Value" ""
			(at 0 0 0)
			(layer "F.Fab")
			(effects
				(font
					(size 1.27 1.27)
				)
			)
		)
		(duplicate_pad_numbers_are_jumpers no)
		(fp_line
			(start -0.7874 -0.4064)
			(end 0.7874 -0.4064)
			(stroke
				(width 0.1524)
				(type default)
			)
			(layer "F.SilkS")
		)
		(fp_line
			(start -0.7874 0.4064)
			(end -0.7874 -0.4064)
			(stroke
				(width 0.1524)
				(type default)
			)
			(layer "F.SilkS")
		)
		(fp_line
			(start 0.7874 -0.4064)
			(end 0.7874 0.4064)
			(stroke
				(width 0.1524)
				(type default)
			)
			(layer "F.SilkS")
		)
		(fp_line
			(start 0.7874 0.4064)
			(end -0.7874 0.4064)
			(stroke
				(width 0.1524)
				(type default)
			)
			(layer "F.SilkS")
		)
		(fp_line
			(start -0.67945 -0.305054)
			(end -0.12065 -0.305054)
			(stroke
				(width 0.1)
				(type default)
			)
			(layer "F.Fab")
		)
		(fp_line
			(start -0.67945 0.3048)
			(end -0.67945 -0.305054)
			(stroke
				(width 0.1)
				(type default)
			)
			(layer "F.Fab")
		)
		(fp_line
			(start -0.12065 -0.305054)
			(end -0.12065 -0.2794)
			(stroke
				(width 0.1)
				(type default)
			)
			(layer "F.Fab")
		)
		(fp_line
			(start -0.12065 -0.2794)
			(end 0.12065 -0.2794)
			(stroke
				(width 0.1)
				(type default)
			)
			(layer "F.Fab")
		)
		(fp_line
			(start -0.12065 0.2794)
			(end -0.12065 0.3048)
			(stroke
				(width 0.1)
				(type default)
			)
			(layer "F.Fab")
		)
		(fp_line
			(start -0.12065 0.3048)
			(end -0.67945 0.3048)
			(stroke
				(width 0.1)
				(type default)
			)
			(layer "F.Fab")
		)
		(fp_line
			(start 0.120396 0.2794)
			(end -0.12065 0.2794)
			(stroke
				(width 0.1)
				(type default)
			)
			(layer "F.Fab")
		)
		(fp_line
			(start 0.120396 0.3048)
			(end 0.120396 0.2794)
			(stroke
				(width 0.1)
				(type default)
			)
			(layer "F.Fab")
		)
		(fp_line
			(start 0.12065 -0.3048)
			(end 0.67945 -0.3048)
			(stroke
				(width 0.1)
				(type default)
			)
			(layer "F.Fab")
		)
		(fp_line
			(start 0.12065 -0.2794)
			(end 0.12065 -0.3048)
			(stroke
				(width 0.1)
				(type default)
			)
			(layer "F.Fab")
		)
		(fp_line
			(start 0.67945 -0.3048)
			(end 0.67945 0.3048)
			(stroke
				(width 0.1)
				(type default)
			)
			(layer "F.Fab")
		)
		(fp_line
			(start 0.67945 0.3048)
			(end 0.120396 0.3048)
			(stroke
				(width 0.1)
				(type default)
			)
			(layer "F.Fab")
		)
		(pad "1" smd circle
			(at -0.40005 0)
			(size 0 0)
			(layers "F.Cu" "F.Mask" "F.Paste")
			(net "P3V3_AUX")
		)
		(pad "2" smd circle
			(at 0.40005 0)
			(size 0 0)
			(layers "F.Cu" "F.Mask" "F.Paste")
			(net "PWRGD_PVDDCR_CPU1_P0_R")
		)
	)
)
